# SCM (Grand Teton) — schematic netlist excerpt (pin names and nets, part order shuffled) for the footprints in the layout excerpt that follows; sources: Cadence DE-HDL packaged netlist, KiCad conversion of 12092022_DA0F0TMDCD0_F0T_Management_Board_D_brd_V3_OCP.brd

R549  Q_RES  33.2 1% CHIP  pkg 0402LF  page 21 : A = SPI_BMC_CLK_FLASH_R ; B = SPI_BMC_BOOT_CLK

Q12  MOSFET_DUAL_6P  2N7002KDW IC  pkg SOT363XD  page 49
  S1  = GND
  G1  = PWR_LED
  D2  = HDD_LED_BUF
  S2  = GND
  G2  = HDD_LED_N
  D1  = PWR_LED_BUF_N

(kicad_pcb
	(version 20260206)
	(generator "pcbnew")
	(generator_version "10.0")
	(general
		(thickness 1.6)
		(legacy_teardrops no)
	)
	(paper "A4")
	(title_block
		(title "12092022_DA0F0TMDCD0_F0T_Management_Board_D_brd_V3_OCP.brd")
		(comment 1 "Grand Teton / footprints 77-78 of 1440")
	)
	(layers
		(0 "F.Cu" signal "TOP")
		(4 "In1.Cu" signal "GND")
		(6 "In2.Cu" signal "IN1")
		(8 "In3.Cu" signal "GND1")
		(10 "In4.Cu" signal "IN2")
		(12 "In5.Cu" signal "VCC")
		(14 "In6.Cu" signal "VCC1")
		(16 "In7.Cu" signal "IN3")
		(18 "In8.Cu" signal "GND2")
		(20 "In9.Cu" signal "IN4")
		(22 "In10.Cu" signal "GND3")
		(2 "B.Cu" signal "BOTTOM")
		(9 "F.Adhes" user "F.Adhesive")
		(11 "B.Adhes" user "B.Adhesive")
		(13 "F.Paste" user "Package Geometry/Pastemask Top")
		(15 "B.Paste" user "Package Geometry/Pastemask Bottom")
		(5 "F.SilkS" user "Ref Des/Silkscreen Top")
		(7 "B.SilkS" user "Ref Des/Silkscreen Bottom")
		(1 "F.Mask" user "Board Geometry/Soldermask Top")
		(3 "B.Mask" user "Board Geometry/Soldermask Bottom")
		(17 "Dwgs.User" user "User.Drawings")
		(19 "Cmts.User" user "User.Comments")
		(21 "Eco1.User" user "User.Eco1")
		(23 "Eco2.User" user "User.Eco2")
		(25 "Edge.Cuts" user "Board Geometry/Outline")
		(27 "Margin" user)
		(31 "F.CrtYd" user "Package Geometry/Place Bound Top")
		(29 "B.CrtYd" user "Package Geometry/Place Bound Bottom")
		(35 "F.Fab" user "Ref Des/Assembly Top")
		(33 "B.Fab" user "Ref Des/Assembly Bottom")
	)
	(footprint ""
		(layer "F.Cu")
		(at 39.8272 -77.4954)
		(property "Reference" "R549"
			(at 0 0 0)
			(layer "F.SilkS")
			(hide yes)
			(effects
				(font
					(size 1.27 1.27)
				)
			)
		)
		(property "Value" ""
			(at 0 0 0)
			(layer "F.Fab")
			(effects
				(font
					(size 1.27 1.27)
				)
			)
		)
		(duplicate_pad_numbers_are_jumpers no)
		(fp_line
			(start -0.7874 -0.4064)
			(end 0.7874 -0.4064)
			(stroke
				(width 0.1524)
				(type default)
			)
			(layer "F.SilkS")
		)
		(fp_line
			(start -0.7874 0.4064)
			(end -0.7874 -0.4064)
			(stroke
				(width 0.1524)
				(type default)
			)
			(layer "F.SilkS")
		)
		(fp_line
			(start 0.7874 -0.4064)
			(end 0.7874 0.4064)
			(stroke
				(width 0.1524)
				(type default)
			)
			(layer "F.SilkS")
		)
		(fp_line
			(start 0.7874 0.4064)
			(end -0.7874 0.4064)
			(stroke
				(width 0.1524)
				(type default)
			)
			(layer "F.SilkS")
		)
		(fp_line
			(start -0.67945 -0.305054)
			(end -0.12065 -0.305054)
			(stroke
				(width 0.1)
				(type default)
			)
			(layer "F.Fab")
		)
		(fp_line
			(start -0.67945 0.3048)
			(end -0.67945 -0.305054)
			(stroke
				(width 0.1)
				(type default)
			)
			(layer "F.Fab")
		)
		(fp_line
			(start -0.12065 -0.305054)
			(end -0.12065 -0.2794)
			(stroke
				(width 0.1)
				(type default)
			)
			(layer "F.Fab")
		)
		(fp_line
			(start -0.12065 -0.2794)
			(end 0.12065 -0.2794)
			(stroke
				(width 0.1)
				(type default)
			)
			(layer "F.Fab")
		)
		(fp_line
			(start -0.12065 0.2794)
			(end -0.12065 0.3048)
			(stroke
				(width 0.1)
				(type default)
			)
			(layer "F.Fab")
		)
		(fp_line
			(start -0.12065 0.3048)
			(end -0.67945 0.3048)
			(stroke
				(width 0.1)
				(type default)
			)
			(layer "F.Fab")
		)
		(fp_line
			(start 0.120396 0.2794)
			(end -0.12065 0.2794)
			(stroke
				(width 0.1)
				(type default)
			)
			(layer "F.Fab")
		)
		(fp_line
			(start 0.120396 0.3048)
			(end 0.120396 0.2794)
			(stroke
				(width 0.1)
				(type default)
			)
			(layer "F.Fab")
		)
		(fp_line
			(start 0.12065 -0.3048)
			(end 0.67945 -0.3048)
			(stroke
				(width 0.1)
				(type default)
			)
			(layer "F.Fab")
		)
		(fp_line
			(start 0.12065 -0.2794)
			(end 0.12065 -0.3048)
			(stroke
				(width 0.1)
				(type default)
			)
			(layer "F.Fab")
		)
		(fp_line
			(start 0.67945 -0.3048)
			(end 0.67945 0.3048)
			(stroke
				(width 0.1)
				(type default)
			)
			(layer "F.Fab")
		)
		(fp_line
			(start 0.67945 0.3048)
			(end 0.120396 0.3048)
			(stroke
				(width 0.1)
				(type default)
			)
			(layer "F.Fab")
		)
		(pad "1" smd circle
			(at -0.40005 0)
			(size 0 0)
			(layers "F.Cu" "F.Mask" "F.Paste")
			(net "SPI_BMC_CLK_FLASH_R")
		)
		(pad "2" smd circle
			(at 0.40005 0)
			(size 0 0)
			(layers "F.Cu" "F.Mask" "F.Paste")
			(net "SPI_BMC_BOOT_CLK")
		)
	)
	(footprint ""
		(layer "F.Cu")
		(at 11.303 -17.399 -90)
		(property "Reference" "Q12"
			(at -0.714502 1.600708 90)
			(unlocked yes)
			(layer "F.SilkS")
			(effects
				(font
					(size 0.7874 0.5842)
					(thickness 0.1524)
				)
				(justify left)
			)
		)
		(property "Value" ""
			(at 0 0 270)
			(layer "F.Fab")
			(effects
				(font
					(size 1.27 1.27)
				)
			)
		)
		(duplicate_pad_numbers_are_jumpers no)
		(fp_line
			(start -1.332738 1.100074)
			(end -1.332738 -1.100074)
			(stroke
				(width 0.1524)
				(type default)
			)
			(layer "F.SilkS")
		)
		(fp_line
			(start 1.332738 1.100074)
			(end -1.332738 1.100074)
			(stroke
				(width 0.1524)
				(type default)
			)
			(layer "F.SilkS")
		)
		(fp_line
			(start 0 -0.541274)
			(end 0.4826 -1.100074)
			(stroke
				(width 0.1524)
				(type default)
			)
			(layer "F.SilkS")
		)
		(fp_line
			(start -1.332738 -1.100074)
			(end -0.4826 -1.100074)
			(stroke
				(width 0.1524)
				(type default)
			)
			(layer "F.SilkS")
		)
		(fp_line
			(start -0.4826 -1.100074)
			(end 0 -0.541274)
			(stroke
				(width 0.1524)
				(type default)
			)
			(layer "F.SilkS")
		)
		(fp_line
			(start 0.4826 -1.100074)
			(end 1.332738 -1.100074)
			(stroke
				(width 0.1524)
				(type default)
			)
			(layer "F.SilkS")
		)
		(fp_line
			(start 1.332738 -1.100074)
			(end 1.332738 1.100074)
			(stroke
				(width 0.1524)
				(type default)
			)
			(layer "F.SilkS")
		)
		(fp_poly
			(pts
				(xy -1.78181 0.260604) (xy -2.278126 -0.235712) (xy -1.533398 -0.484124)
			)
			(stroke
				(width 0)
				(type default)
			)
			(fill yes)
			(layer "F.SilkS")
		)
		(fp_line
			(start -0.674878 1.100074)
			(end -0.674878 -1.100074)
			(stroke
				(width 0.1)
				(type default)
			)
			(layer "F.Fab")
		)
		(fp_line
			(start 0.674878 1.100074)
			(end -0.674878 1.100074)
			(stroke
				(width 0.1)
				(type default)
			)
			(layer "F.Fab")
		)
		(fp_line
			(start -0.674878 -1.100074)
			(end 0.674878 -1.100074)
			(stroke
				(width 0.1)
				(type default)
			)
			(layer "F.Fab")
		)
		(fp_line
			(start 0.674878 -1.100074)
			(end 0.674878 1.100074)
			(stroke
				(width 0.1)
				(type default)
			)
			(layer "F.Fab")
		)
		(fp_poly
			(pts
				(xy -2.2352 -0.298958) (xy -2.2352 -1.001014) (xy -1.533144 -0.649986)
			)
			(stroke
				(width 0)
				(type default)
			)
			(fill yes)
			(layer "F.Fab")
		)
		(pad "1" smd rect
			(at -0.94996 -0.649986)
			(size 0.4318 0.508)
			(layers "F.Cu" "F.Mask" "F.Paste")
			(net "GND")
		)
		(pad "2" smd rect
			(at -0.94996 0)
			(size 0.4318 0.508)
			(layers "F.Cu" "F.Mask" "F.Paste")
			(net "PWR_LED")
		)
		(pad "3" smd rect
			(at -0.94996 0.649986)
			(size 0.4318 0.508)
			(layers "F.Cu" "F.Mask" "F.Paste")
			(net "HDD_LED_BUF")
		)
		(pad "4" smd rect
			(at 0.94996 0.649986)
			(size 0.4318 0.508)
			(layers "F.Cu" "F.Mask" "F.Paste")
			(net "GND")
		)
		(pad "5" smd rect
			(at 0.94996 0)
			(size 0.4318 0.508)
			(layers "F.Cu" "F.Mask" "F.Paste")
			(net "HDD_LED_N")
		)
		(pad "6" smd rect
			(at 0.94996 -0.649986)
			(size 0.4318 0.508)
			(layers "F.Cu" "F.Mask" "F.Paste")
			(net "PWR_LED_BUF_N")
		)
	)
)
